# T6G (Grand Teton) — schematic netlist excerpt (pin names and nets, part order shuffled) for the footprints in the layout excerpt that follows; sources: Cadence DE-HDL packaged netlist, KiCad conversion of 04192023_DAF0TMB3IC0_F0TG_MB_C_brd_V02_OCP.brd

C1075  Q_CAP  0.1UF 25V 10% X7R  pkg 0402  page 258 : A = P3V3_MAX11617_2_VDD ; B = GND
R6798  Q_RES  0 5% CHIP  pkg 0402LF  page 81 : A = RST_RT_CPU1_P3_PERST_R_N ; B = RST_RT_CPU1_P3_PERST_R2_N

(kicad_pcb
	(version 20260206)
	(generator "pcbnew")
	(generator_version "10.0")
	(general
		(thickness 1.6)
		(legacy_teardrops no)
	)
	(paper "A4")
	(title_block
		(title "04192023_DAF0TMB3IC0_F0TG_MB_C_brd_V02_OCP.brd")
		(comment 1 "Grand Teton / footprints 6588-6589 of 8354")
	)
	(layers
		(0 "F.Cu" signal "TOP")
		(4 "In1.Cu" signal "GND")
		(6 "In2.Cu" signal "IN1")
		(8 "In3.Cu" signal "GND1")
		(10 "In4.Cu" signal "IN2")
		(12 "In5.Cu" signal "GND2")
		(14 "In6.Cu" signal "IN3")
		(16 "In7.Cu" signal "GND3")
		(18 "In8.Cu" signal "VCC")
		(20 "In9.Cu" signal "VCC1")
		(22 "In10.Cu" signal "GND4")
		(24 "In11.Cu" signal "IN4")
		(26 "In12.Cu" signal "GND5")
		(28 "In13.Cu" signal "IN5")
		(30 "In14.Cu" signal "GND6")
		(32 "In15.Cu" signal "IN6")
		(34 "In16.Cu" signal "GND7")
		(2 "B.Cu" signal "BOTTOM")
		(9 "F.Adhes" user "F.Adhesive")
		(11 "B.Adhes" user "B.Adhesive")
		(13 "F.Paste" user "Package Geometry/Pastemask Top")
		(15 "B.Paste" user "Package Geometry/Pastemask Bottom")
		(5 "F.SilkS" user "Ref Des/Silkscreen Top")
		(7 "B.SilkS" user "Ref Des/Silkscreen Bottom")
		(1 "F.Mask" user "Board Geometry/Soldermask Top")
		(3 "B.Mask" user "Board Geometry/Soldermask Bottom")
		(17 "Dwgs.User" user "User.Drawings")
		(19 "Cmts.User" user "User.Comments")
		(21 "Eco1.User" user "User.Eco1")
		(23 "Eco2.User" user "User.Eco2")
		(25 "Edge.Cuts" user "Board Geometry/Outline")
		(27 "Margin" user)
		(31 "F.CrtYd" user "Package Geometry/Place Bound Top")
		(29 "B.CrtYd" user "Package Geometry/Place Bound Bottom")
		(35 "F.Fab" user "Ref Des/Assembly Top")
		(33 "B.Fab" user "Ref Des/Assembly Bottom")
	)
	(footprint ""
		(layer "B.Cu")
		(at 186.230514 -131.556506 90)
		(property "Reference" "R6798"
			(at 0 0 90)
			(layer "B.SilkS")
			(hide yes)
			(effects
				(font
					(size 1.27 1.27)
				)
				(justify mirror)
			)
		)
		(property "Value" ""
			(at 0 0 90)
			(layer "B.Fab")
			(effects
				(font
					(size 1.27 1.27)
				)
				(justify mirror)
			)
		)
		(duplicate_pad_numbers_are_jumpers no)
		(fp_line
			(start 0.7874 -0.4064)
			(end -0.7874 -0.4064)
			(stroke
				(width 0.1524)
				(type default)
			)
			(layer "B.SilkS")
		)
		(fp_line
			(start -0.7874 -0.4064)
			(end -0.7874 0.4064)
			(stroke
				(width 0.1524)
				(type default)
			)
			(layer "B.SilkS")
		)
		(fp_line
			(start 0.7874 0.4064)
			(end 0.7874 -0.4064)
			(stroke
				(width 0.1524)
				(type default)
			)
			(layer "B.SilkS")
		)
		(fp_line
			(start -0.7874 0.4064)
			(end 0.7874 0.4064)
			(stroke
				(width 0.1524)
				(type default)
			)
			(layer "B.SilkS")
		)
		(fp_line
			(start 0.67945 -0.305054)
			(end 0.12065 -0.305054)
			(stroke
				(width 0.1)
				(type default)
			)
			(layer "B.Fab")
		)
		(fp_line
			(start 0.12065 -0.305054)
			(end 0.12065 -0.2794)
			(stroke
				(width 0.1)
				(type default)
			)
			(layer "B.Fab")
		)
		(fp_line
			(start -0.12065 -0.3048)
			(end -0.67945 -0.3048)
			(stroke
				(width 0.1)
				(type default)
			)
			(layer "B.Fab")
		)
		(fp_line
			(start -0.67945 -0.3048)
			(end -0.67945 0.3048)
			(stroke
				(width 0.1)
				(type default)
			)
			(layer "B.Fab")
		)
		(fp_line
			(start 0.12065 -0.2794)
			(end -0.12065 -0.2794)
			(stroke
				(width 0.1)
				(type default)
			)
			(layer "B.Fab")
		)
		(fp_line
			(start -0.12065 -0.2794)
			(end -0.12065 -0.3048)
			(stroke
				(width 0.1)
				(type default)
			)
			(layer "B.Fab")
		)
		(fp_line
			(start 0.12065 0.2794)
			(end 0.12065 0.3048)
			(stroke
				(width 0.1)
				(type default)
			)
			(layer "B.Fab")
		)
		(fp_line
			(start -0.120396 0.2794)
			(end 0.12065 0.2794)
			(stroke
				(width 0.1)
				(type default)
			)
			(layer "B.Fab")
		)
		(fp_line
			(start 0.67945 0.3048)
			(end 0.67945 -0.305054)
			(stroke
				(width 0.1)
				(type default)
			)
			(layer "B.Fab")
		)
		(fp_line
			(start 0.12065 0.3048)
			(end 0.67945 0.3048)
			(stroke
				(width 0.1)
				(type default)
			)
			(layer "B.Fab")
		)
		(fp_line
			(start -0.120396 0.3048)
			(end -0.120396 0.2794)
			(stroke
				(width 0.1)
				(type default)
			)
			(layer "B.Fab")
		)
		(fp_line
			(start -0.67945 0.3048)
			(end -0.120396 0.3048)
			(stroke
				(width 0.1)
				(type default)
			)
			(layer "B.Fab")
		)
		(pad "1" smd circle
			(at 0.40005 0 270)
			(size 0 0)
			(layers "B.Cu" "B.Mask" "B.Paste")
			(net "RST_RT_CPU1_P3_PERST_R_N")
		)
		(pad "2" smd circle
			(at -0.40005 0 270)
			(size 0 0)
			(layers "B.Cu" "B.Mask" "B.Paste")
			(net "RST_RT_CPU1_P3_PERST_R2_N")
		)
	)
	(footprint ""
		(layer "B.Cu")
		(at 245.745 -329.184 -90)
		(property "Reference" "C1075"
			(at 0 0 90)
			(layer "B.SilkS")
			(hide yes)
			(effects
				(font
					(size 1.27 1.27)
				)
				(justify mirror)
			)
		)
		(property "Value" ""
			(at 0 0 90)
			(layer "B.Fab")
			(effects
				(font
					(size 1.27 1.27)
				)
				(justify mirror)
			)
		)
		(duplicate_pad_numbers_are_jumpers no)
		(fp_line
			(start -0.7874 0.4064)
			(end 0.7874 0.4064)
			(stroke
				(width 0.1524)
				(type default)
			)
			(layer "B.SilkS")
		)
		(fp_line
			(start 0.7874 0.4064)
			(end 0.7874 -0.4064)
			(stroke
				(width 0.1524)
				(type default)
			)
			(layer "B.SilkS")
		)
		(fp_line
			(start -0.7874 -0.4064)
			(end -0.7874 0.4064)
			(stroke
				(width 0.1524)
				(type default)
			)
			(layer "B.SilkS")
		)
		(fp_line
			(start 0.7874 -0.4064)
			(end -0.7874 -0.4064)
			(stroke
				(width 0.1524)
				(type default)
			)
			(layer "B.SilkS")
		)
		(fp_line
			(start -0.67945 0.3048)
			(end -0.120396 0.3048)
			(stroke
				(width 0.1)
				(type default)
			)
			(layer "B.Fab")
		)
		(fp_line
			(start -0.120396 0.3048)
			(end -0.120396 0.2794)
			(stroke
				(width 0.1)
				(type default)
			)
			(layer "B.Fab")
		)
		(fp_line
			(start 0.12065 0.3048)
			(end 0.67945 0.3048)
			(stroke
				(width 0.1)
				(type default)
			)
			(layer "B.Fab")
		)
		(fp_line
			(start 0.67945 0.3048)
			(end 0.67945 -0.305054)
			(stroke
				(width 0.1)
				(type default)
			)
			(layer "B.Fab")
		)
		(fp_line
			(start -0.120396 0.2794)
			(end 0.12065 0.2794)
			(stroke
				(width 0.1)
				(type default)
			)
			(layer "B.Fab")
		)
		(fp_line
			(start 0.12065 0.2794)
			(end 0.12065 0.3048)
			(stroke
				(width 0.1)
				(type default)
			)
			(layer "B.Fab")
		)
		(fp_line
			(start -0.12065 -0.2794)
			(end -0.12065 -0.3048)
			(stroke
				(width 0.1)
				(type default)
			)
			(layer "B.Fab")
		)
		(fp_line
			(start 0.12065 -0.2794)
			(end -0.12065 -0.2794)
			(stroke
				(width 0.1)
				(type default)
			)
			(layer "B.Fab")
		)
		(fp_line
			(start -0.67945 -0.3048)
			(end -0.67945 0.3048)
			(stroke
				(width 0.1)
				(type default)
			)
			(layer "B.Fab")
		)
		(fp_line
			(start -0.12065 -0.3048)
			(end -0.67945 -0.3048)
			(stroke
				(width 0.1)
				(type default)
			)
			(layer "B.Fab")
		)
		(fp_line
			(start 0.12065 -0.305054)
			(end 0.12065 -0.2794)
			(stroke
				(width 0.1)
				(type default)
			)
			(layer "B.Fab")
		)
		(fp_line
			(start 0.67945 -0.305054)
			(end 0.12065 -0.305054)
			(stroke
				(width 0.1)
				(type default)
			)
			(layer "B.Fab")
		)
		(pad "1" smd circle
			(at 0.40005 0 90)
			(size 0 0)
			(layers "B.Cu" "B.Mask" "B.Paste")
			(net "P3V3_MAX11617_2_VDD")
		)
		(pad "2" smd circle
			(at -0.40005 0 90)
			(size 0 0)
			(layers "B.Cu" "B.Mask" "B.Paste")
			(net "GND")
		)
	)
)
